(kicad_pcb
	(version 20260206)
	(generator "pcbnew")
	(generator_version "10.0")
	(general
		(thickness 1.6)
		(legacy_teardrops no)
	)
	(paper "A4")
	(title_block
		(title "dpb — 14545-sa.0730WZS0815.brd")
		(comment 1 "Honey Badger (Wiwynn) / footprints 266-272 of 1066")
	)
	(layers
		(0 "F.Cu" signal "TOP")
		(4 "In1.Cu" signal "L2GND")
		(6 "In2.Cu" signal "L3")
		(8 "In3.Cu" signal "L4VCC")
		(10 "In4.Cu" signal "L5VCC")
		(12 "In5.Cu" signal "L6")
		(14 "In6.Cu" signal "L7GND")
		(2 "B.Cu" signal "BOTTOM")
		(9 "F.Adhes" user "F.Adhesive")
		(11 "B.Adhes" user "B.Adhesive")
		(13 "F.Paste" user "Package Geometry/Pastemask Top")
		(15 "B.Paste" user "Package Geometry/Pastemask Bottom")
		(5 "F.SilkS" user "Ref Des/Silkscreen Top")
		(7 "B.SilkS" user "Ref Des/Silkscreen Bottom")
		(1 "F.Mask" user "Board Geometry/Soldermask Top")
		(3 "B.Mask" user "Board Geometry/Soldermask Bottom")
		(17 "Dwgs.User" user "User.Drawings")
		(19 "Cmts.User" user "User.Comments")
		(21 "Eco1.User" user "User.Eco1")
		(23 "Eco2.User" user "User.Eco2")
		(25 "Edge.Cuts" user "Board Geometry/Outline")
		(27 "Margin" user)
		(31 "F.CrtYd" user "Package Geometry/Place Bound Top")
		(29 "B.CrtYd" user "Package Geometry/Place Bound Bottom")
		(35 "F.Fab" user "Ref Des/Assembly Top")
		(33 "B.Fab" user "Ref Des/Assembly Bottom")
	)
	(footprint ""
		(layer "F.Cu")
		(at 14.715744 -260.3627 -90)
		(property "Reference" "R272"
			(at 0 0 270)
			(layer "F.SilkS")
			(hide yes)
			(effects
				(font
					(size 1.27 1.27)
				)
			)
		)
		(property "Value" "0R2J-2-GP"
			(at 0.064008 -3.993896 270)
			(unlocked yes)
			(layer "F.Fab")
			(hide yes)
			(effects
				(font
					(size 1.016 1.016)
					(thickness 0.1524)
				)
			)
		)
		(property "Device Type" "R402H16"
			(at 0.064008 -5.517896 270)
			(unlocked yes)
			(layer "F.Fab")
			(hide yes)
			(effects
				(font
					(size 1.016 1.016)
					(thickness 0.1524)
				)
			)
		)
		(duplicate_pad_numbers_are_jumpers no)
		(fp_line
			(start -0.508 -0.9398)
			(end -0.508 0.9398)
			(stroke
				(width 0.1524)
				(type default)
			)
			(layer "F.SilkS")
		)
		(fp_line
			(start 0.508 -0.9398)
			(end -0.508 -0.9398)
			(stroke
				(width 0.1524)
				(type default)
			)
			(layer "F.SilkS")
		)
		(fp_rect
			(start -0.508 0.9398)
			(end 0.508 -0.9398)
			(stroke
				(width 0)
				(type default)
			)
			(fill no)
			(layer "F.CrtYd")
		)
		(fp_rect
			(start -0.508 0.9398)
			(end 0.508 -0.9398)
			(stroke
				(width 0)
				(type default)
			)
			(fill no)
			(layer "F.Fab")
		)
		(pad "1" smd custom
			(at 0 -0.4445 270)
			(size 0.1397 0.1397)
			(layers "F.Cu" "F.Mask" "F.Paste")
			(net "FLT_NET_HDD12")
			(options
				(clearance outline)
				(anchor circle)
			)
			(primitives
				(gr_poly
					(pts
						(arc
							(start -0.1778 -0.2794)
							(mid -0.249642 -0.249642)
							(end -0.2794 -0.1778)
						)
						(arc
							(start -0.2794 0.1778)
							(mid -0.249642 0.249642)
							(end -0.1778 0.2794)
						)
						(arc
							(start 0.1778 0.2794)
							(mid 0.249642 0.249642)
							(end 0.2794 0.1778)
						)
						(arc
							(start 0.2794 -0.1778)
							(mid 0.249642 -0.249642)
							(end 0.1778 -0.2794)
						)
					)
					(width 0)
					(fill yes)
				)
			)
		)
		(pad "2" smd custom
			(at 0 0.4445 270)
			(size 0.1397 0.1397)
			(layers "F.Cu" "F.Mask" "F.Paste")
			(net "FLT_HDD12_DRIVE")
			(options
				(clearance outline)
				(anchor circle)
			)
			(primitives
				(gr_poly
					(pts
						(arc
							(start -0.1778 -0.2794)
							(mid -0.249642 -0.249642)
							(end -0.2794 -0.1778)
						)
						(arc
							(start -0.2794 0.1778)
							(mid -0.249642 0.249642)
							(end -0.1778 0.2794)
						)
						(arc
							(start 0.1778 0.2794)
							(mid 0.249642 0.249642)
							(end 0.2794 0.1778)
						)
						(arc
							(start 0.2794 -0.1778)
							(mid 0.249642 -0.249642)
							(end 0.1778 -0.2794)
						)
					)
					(width 0)
					(fill yes)
				)
			)
		)
	)
	(footprint ""
		(layer "F.Cu")
		(at 199.263 -487.934)
		(property "Reference" "C102"
			(at 0 0 0)
			(layer "F.SilkS")
			(hide yes)
			(effects
				(font
					(size 1.27 1.27)
				)
			)
		)
		(property "Value" "SCD1U10V2KX-5GP"
			(at 1.1811 -2.7051 0)
			(unlocked yes)
			(layer "F.Fab")
			(hide yes)
			(effects
				(font
					(size 1.016 1.016)
					(thickness 0.1524)
				)
			)
		)
		(property "Device Type" "C402H22"
			(at 1.1811 -4.2291 0)
			(unlocked yes)
			(layer "F.Fab")
			(hide yes)
			(effects
				(font
					(size 1.016 1.016)
					(thickness 0.1524)
				)
			)
		)
		(duplicate_pad_numbers_are_jumpers no)
		(fp_rect
			(start -0.4318 0.9525)
			(end 0.4318 -0.9525)
			(stroke
				(width 0)
				(type default)
			)
			(fill no)
			(layer "F.CrtYd")
		)
		(fp_rect
			(start -0.4318 0.9525)
			(end 0.4318 -0.9525)
			(stroke
				(width 0)
				(type default)
			)
			(fill no)
			(layer "F.Fab")
		)
		(pad "1" smd custom
			(at 0 -0.4445)
			(size 0.1524 0.1524)
			(layers "F.Cu" "F.Mask" "F.Paste")
			(net "P3V3")
			(options
				(clearance outline)
				(anchor circle)
			)
			(primitives
				(gr_poly
					(pts
						(arc
							(start 0.3048 -0.2032)
							(mid 0.275042 -0.275042)
							(end 0.2032 -0.3048)
						)
						(arc
							(start -0.2032 -0.3048)
							(mid -0.275042 -0.275042)
							(end -0.3048 -0.2032)
						)
						(arc
							(start -0.3048 0.2032)
							(mid -0.275042 0.275042)
							(end -0.2032 0.3048)
						)
						(arc
							(start 0.2032 0.3048)
							(mid 0.275042 0.275042)
							(end 0.3048 0.2032)
						)
					)
					(width 0)
					(fill yes)
				)
			)
		)
		(pad "2" smd custom
			(at 0 0.4445)
			(size 0.1524 0.1524)
			(layers "F.Cu" "F.Mask" "F.Paste")
			(net "GND")
			(options
				(clearance outline)
				(anchor circle)
			)
			(primitives
				(gr_poly
					(pts
						(arc
							(start 0.3048 -0.2032)
							(mid 0.275042 -0.275042)
							(end 0.2032 -0.3048)
						)
						(arc
							(start -0.2032 -0.3048)
							(mid -0.275042 -0.275042)
							(end -0.3048 -0.2032)
						)
						(arc
							(start -0.3048 0.2032)
							(mid -0.275042 0.275042)
							(end -0.2032 0.3048)
						)
						(arc
							(start 0.2032 0.3048)
							(mid 0.275042 0.275042)
							(end 0.3048 0.2032)
						)
					)
					(width 0)
					(fill yes)
				)
			)
		)
	)
	(footprint ""
		(layer "F.Cu")
		(at 21.399246 -465.483702 -90)
		(property "Reference" "R243"
			(at 0 0 270)
			(layer "F.SilkS")
			(hide yes)
			(effects
				(font
					(size 1.27 1.27)
				)
			)
		)
		(property "Value" "330R2F-GP"
			(at 0.064008 -3.993896 270)
			(unlocked yes)
			(layer "F.Fab")
			(hide yes)
			(effects
				(font
					(size 1.016 1.016)
					(thickness 0.1524)
				)
			)
		)
		(property "Device Type" "R402H16"
			(at 0.064008 -5.517896 270)
			(unlocked yes)
			(layer "F.Fab")
			(hide yes)
			(effects
				(font
					(size 1.016 1.016)
					(thickness 0.1524)
				)
			)
		)
		(duplicate_pad_numbers_are_jumpers no)
		(fp_line
			(start -0.508 -0.9398)
			(end -0.508 0.9398)
			(stroke
				(width 0.1524)
				(type default)
			)
			(layer "F.SilkS")
		)
		(fp_line
			(start 0.508 -0.9398)
			(end -0.508 -0.9398)
			(stroke
				(width 0.1524)
				(type default)
			)
			(layer "F.SilkS")
		)
		(fp_rect
			(start -0.508 0.9398)
			(end 0.508 -0.9398)
			(stroke
				(width 0)
				(type default)
			)
			(fill no)
			(layer "F.CrtYd")
		)
		(fp_rect
			(start -0.508 0.9398)
			(end 0.508 -0.9398)
			(stroke
				(width 0)
				(type default)
			)
			(fill no)
			(layer "F.Fab")
		)
		(pad "1" smd custom
			(at 0 -0.4445 270)
			(size 0.1397 0.1397)
			(layers "F.Cu" "F.Mask" "F.Paste")
			(net "P3V3_HDD10_LED")
			(options
				(clearance outline)
				(anchor circle)
			)
			(primitives
				(gr_poly
					(pts
						(arc
							(start -0.1778 -0.2794)
							(mid -0.249642 -0.249642)
							(end -0.2794 -0.1778)
						)
						(arc
							(start -0.2794 0.1778)
							(mid -0.249642 0.249642)
							(end -0.1778 0.2794)
						)
						(arc
							(start 0.1778 0.2794)
							(mid 0.249642 0.249642)
							(end 0.2794 0.1778)
						)
						(arc
							(start 0.2794 -0.1778)
							(mid 0.249642 -0.249642)
							(end 0.1778 -0.2794)
						)
					)
					(width 0)
					(fill yes)
				)
			)
		)
		(pad "2" smd custom
			(at 0 0.4445 270)
			(size 0.1397 0.1397)
			(layers "F.Cu" "F.Mask" "F.Paste")
			(net "FLT_HDD10")
			(options
				(clearance outline)
				(anchor circle)
			)
			(primitives
				(gr_poly
					(pts
						(arc
							(start -0.1778 -0.2794)
							(mid -0.249642 -0.249642)
							(end -0.2794 -0.1778)
						)
						(arc
							(start -0.2794 0.1778)
							(mid -0.249642 0.249642)
							(end -0.1778 0.2794)
						)
						(arc
							(start 0.1778 0.2794)
							(mid 0.249642 0.249642)
							(end 0.2794 0.1778)
						)
						(arc
							(start 0.2794 -0.1778)
							(mid 0.249642 -0.249642)
							(end 0.1778 -0.2794)
						)
					)
					(width 0)
					(fill yes)
				)
			)
		)
	)
	(footprint ""
		(layer "F.Cu")
		(at 171.335446 -459.901036 -90)
		(property "Reference" "U53"
			(at 0 0 270)
			(layer "F.SilkS")
			(hide yes)
			(effects
				(font
					(size 1.27 1.27)
				)
			)
		)
		(property "Value" "ADS1015IDGSR-GP"
			(at 0 -11.1252 270)
			(unlocked yes)
			(layer "F.Fab")
			(hide yes)
			(effects
				(font
					(size 1.016 1.016)
					(thickness 0.1524)
				)
			)
		)
		(property "Device Type" "MSOP10H44"
			(at 0 -12.6492 270)
			(unlocked yes)
			(layer "F.Fab")
			(hide yes)
			(effects
				(font
					(size 1.016 1.016)
					(thickness 0.1524)
				)
			)
		)
		(duplicate_pad_numbers_are_jumpers no)
		(fp_line
			(start -2.0066 1.016)
			(end -2.0066 -1.016)
			(stroke
				(width 0.1524)
				(type default)
			)
			(layer "F.SilkS")
		)
		(fp_line
			(start -1.8288 1.016)
			(end -1.8288 3.048)
			(stroke
				(width 0.508)
				(type default)
			)
			(layer "F.SilkS")
		)
		(fp_line
			(start 1.143 1.016)
			(end -2.0066 1.016)
			(stroke
				(width 0.1524)
				(type default)
			)
			(layer "F.SilkS")
		)
		(fp_line
			(start -1.5748 0)
			(end -1.9558 0.381)
			(stroke
				(width 0.1524)
				(type default)
			)
			(layer "F.SilkS")
		)
		(fp_line
			(start -1.5748 0)
			(end -1.9558 -0.381)
			(stroke
				(width 0.1524)
				(type default)
			)
			(layer "F.SilkS")
		)
		(fp_line
			(start -2.0066 -1.016)
			(end 1.143 -1.016)
			(stroke
				(width 0.1524)
				(type default)
			)
			(layer "F.SilkS")
		)
		(fp_line
			(start 1.143 -1.016)
			(end 1.143 1.016)
			(stroke
				(width 0.1524)
				(type default)
			)
			(layer "F.SilkS")
		)
		(fp_poly
			(pts
				(xy -2.0828 3.3401) (xy 2.0828 3.3401) (xy 2.0828 -3.3401) (xy -2.0828 -3.3401)
			)
			(stroke
				(width 0)
				(type default)
			)
			(fill no)
			(layer "F.CrtYd")
		)
		(fp_poly
			(pts
				(xy -2.0828 3.3401) (xy 2.0828 3.3401) (xy 2.0828 -3.3401) (xy -2.0828 -3.3401)
			)
			(stroke
				(width 0)
				(type default)
			)
			(fill no)
			(layer "F.Fab")
		)
		(pad "1" smd rect
			(at -0.99949 2.0701 270)
			(size 0.3048 1.524)
			(layers "F.Cu" "F.Mask" "F.Paste")
			(net "VOL_SEN_ADDR")
		)
		(pad "2" smd rect
			(at -0.50038 2.0701 270)
			(size 0.3048 1.524)
			(layers "F.Cu" "F.Mask" "F.Paste")
			(net "VOL_SEN_ALERT")
		)
		(pad "3" smd rect
			(at 0 2.0701 270)
			(size 0.3048 1.524)
			(layers "F.Cu" "F.Mask" "F.Paste")
			(net "GND")
		)
		(pad "4" smd rect
			(at 0.50038 2.0701 270)
			(size 0.3048 1.524)
			(layers "F.Cu" "F.Mask" "F.Paste")
			(net "P5VA_SENSE")
		)
		(pad "5" smd rect
			(at 0.99949 2.0701 270)
			(size 0.3048 1.524)
			(layers "F.Cu" "F.Mask" "F.Paste")
			(net "P5VB_SENSE")
		)
		(pad "6" smd rect
			(at 0.99949 -2.0701 270)
			(size 0.3048 1.524)
			(layers "F.Cu" "F.Mask" "F.Paste")
			(net "P5VC_SENSE")
		)
		(pad "7" smd rect
			(at 0.50038 -2.0701 270)
			(size 0.3048 1.524)
			(layers "F.Cu" "F.Mask" "F.Paste")
			(net "P12V_SENSE")
		)
		(pad "8" smd rect
			(at 0 -2.0701 270)
			(size 0.3048 1.524)
			(layers "F.Cu" "F.Mask" "F.Paste")
			(net "P3V3")
		)
		(pad "9" smd rect
			(at -0.50038 -2.0701 270)
			(size 0.3048 1.524)
			(layers "F.Cu" "F.Mask" "F.Paste")
			(net "VOL_SEN_SDA")
		)
		(pad "10" smd rect
			(at -0.99949 -2.0701 270)
			(size 0.3048 1.524)
			(layers "F.Cu" "F.Mask" "F.Paste")
			(net "VOL_SEN_SCL")
		)
	)
	(footprint ""
		(layer "F.Cu")
		(at 229.615746 -25.1587 90)
		(property "Reference" "PR8"
			(at 0 0 90)
			(layer "F.SilkS")
			(hide yes)
			(effects
				(font
					(size 1.27 1.27)
				)
			)
		)
		(property "Value" "3D01R2F-GP"
			(at 0.064008 -3.993896 90)
			(unlocked yes)
			(layer "F.Fab")
			(hide yes)
			(effects
				(font
					(size 1.016 1.016)
					(thickness 0.1524)
				)
			)
		)
		(property "Device Type" "R402H16"
			(at 0.064008 -5.517896 90)
			(unlocked yes)
			(layer "F.Fab")
			(hide yes)
			(effects
				(font
					(size 1.016 1.016)
					(thickness 0.1524)
				)
			)
		)
		(duplicate_pad_numbers_are_jumpers no)
		(fp_line
			(start 0.508 -0.9398)
			(end -0.508 -0.9398)
			(stroke
				(width 0.1524)
				(type default)
			)
			(layer "F.SilkS")
		)
		(fp_line
			(start -0.508 -0.9398)
			(end -0.508 0.9398)
			(stroke
				(width 0.1524)
				(type default)
			)
			(layer "F.SilkS")
		)
		(fp_rect
			(start -0.508 0.9398)
			(end 0.508 -0.9398)
			(stroke
				(width 0)
				(type default)
			)
			(fill no)
			(layer "F.CrtYd")
		)
		(fp_rect
			(start -0.508 0.9398)
			(end 0.508 -0.9398)
			(stroke
				(width 0)
				(type default)
			)
			(fill no)
			(layer "F.Fab")
		)
		(pad "1" smd custom
			(at 0 -0.4445 90)
			(size 0.1397 0.1397)
			(layers "F.Cu" "F.Mask" "F.Paste")
			(net "GND")
			(options
				(clearance outline)
				(anchor circle)
			)
			(primitives
				(gr_poly
					(pts
						(arc
							(start -0.1778 -0.2794)
							(mid -0.249642 -0.249642)
							(end -0.2794 -0.1778)
						)
						(arc
							(start -0.2794 0.1778)
							(mid -0.249642 0.249642)
							(end -0.1778 0.2794)
						)
						(arc
							(start 0.1778 0.2794)
							(mid 0.249642 0.249642)
							(end 0.2794 0.1778)
						)
						(arc
							(start 0.2794 -0.1778)
							(mid 0.249642 -0.249642)
							(end 0.1778 -0.2794)
						)
					)
					(width 0)
					(fill yes)
				)
			)
		)
		(pad "2" smd custom
			(at 0 0.4445 90)
			(size 0.1397 0.1397)
			(layers "F.Cu" "F.Mask" "F.Paste")
			(net "P5VA_SNB")
			(options
				(clearance outline)
				(anchor circle)
			)
			(primitives
				(gr_poly
					(pts
						(arc
							(start -0.1778 -0.2794)
							(mid -0.249642 -0.249642)
							(end -0.2794 -0.1778)
						)
						(arc
							(start -0.2794 0.1778)
							(mid -0.249642 0.249642)
							(end -0.1778 0.2794)
						)
						(arc
							(start 0.1778 0.2794)
							(mid 0.249642 0.249642)
							(end 0.2794 0.1778)
						)
						(arc
							(start 0.2794 -0.1778)
							(mid 0.249642 -0.249642)
							(end 0.1778 -0.2794)
						)
					)
					(width 0)
					(fill yes)
				)
			)
		)
	)
	(footprint ""
		(layer "F.Cu")
		(at 195.453 -290.449 180)
		(property "Reference" "R410"
			(at 0 0 180)
			(layer "F.SilkS")
			(hide yes)
			(effects
				(font
					(size 1.27 1.27)
				)
			)
		)
		(property "Value" "0R2J-2-GP"
			(at 0.064008 -3.993896 180)
			(unlocked yes)
			(layer "F.Fab")
			(hide yes)
			(effects
				(font
					(size 1.016 1.016)
					(thickness 0.1524)
				)
			)
		)
		(property "Device Type" "R402H16"
			(at 0.064008 -5.517896 180)
			(unlocked yes)
			(layer "F.Fab")
			(hide yes)
			(effects
				(font
					(size 1.016 1.016)
					(thickness 0.1524)
				)
			)
		)
		(duplicate_pad_numbers_are_jumpers no)
		(fp_line
			(start 0.508 -0.9398)
			(end -0.508 -0.9398)
			(stroke
				(width 0.1524)
				(type default)
			)
			(layer "F.SilkS")
		)
		(fp_line
			(start -0.508 -0.9398)
			(end -0.508 0.9398)
			(stroke
				(width 0.1524)
				(type default)
			)
			(layer "F.SilkS")
		)
		(fp_rect
			(start -0.508 0.9398)
			(end 0.508 -0.9398)
			(stroke
				(width 0)
				(type default)
			)
			(fill no)
			(layer "F.CrtYd")
		)
		(fp_rect
			(start -0.508 0.9398)
			(end 0.508 -0.9398)
			(stroke
				(width 0)
				(type default)
			)
			(fill no)
			(layer "F.Fab")
		)
		(pad "1" smd custom
			(at 0 -0.4445 180)
			(size 0.1397 0.1397)
			(layers "F.Cu" "F.Mask" "F.Paste")
			(net "SW_HDD2_G")
			(options
				(clearance outline)
				(anchor circle)
			)
			(primitives
				(gr_poly
					(pts
						(arc
							(start -0.1778 -0.2794)
							(mid -0.249642 -0.249642)
							(end -0.2794 -0.1778)
						)
						(arc
							(start -0.2794 0.1778)
							(mid -0.249642 0.249642)
							(end -0.1778 0.2794)
						)
						(arc
							(start 0.1778 0.2794)
							(mid 0.249642 0.249642)
							(end 0.2794 0.1778)
						)
						(arc
							(start 0.2794 -0.1778)
							(mid 0.249642 -0.249642)
							(end 0.1778 -0.2794)
						)
					)
					(width 0)
					(fill yes)
				)
			)
		)
		(pad "2" smd custom
			(at 0 0.4445 180)
			(size 0.1397 0.1397)
			(layers "F.Cu" "F.Mask" "F.Paste")
			(net "SW_HDD2_R")
			(options
				(clearance outline)
				(anchor circle)
			)
			(primitives
				(gr_poly
					(pts
						(arc
							(start -0.1778 -0.2794)
							(mid -0.249642 -0.249642)
							(end -0.2794 -0.1778)
						)
						(arc
							(start -0.2794 0.1778)
							(mid -0.249642 0.249642)
							(end -0.1778 0.2794)
						)
						(arc
							(start 0.1778 0.2794)
							(mid 0.249642 0.249642)
							(end 0.2794 0.1778)
						)
						(arc
							(start 0.2794 -0.1778)
							(mid 0.249642 -0.249642)
							(end 0.1778 -0.2794)
						)
					)
					(width 0)
					(fill yes)
				)
			)
		)
	)
	(footprint ""
		(layer "F.Cu")
		(at 217.799412 -63.353696 -90)
		(property "Reference" "C168"
			(at 0 0 270)
			(layer "F.SilkS")
			(hide yes)
			(effects
				(font
					(size 1.27 1.27)
				)
			)
		)
		(property "Value" "SCD01U50V2KX-1GP"
			(at 1.1811 -2.7051 270)
			(unlocked yes)
			(layer "F.Fab")
			(hide yes)
			(effects
				(font
					(size 1.016 1.016)
					(thickness 0.1524)
				)
			)
		)
		(property "Device Type" "C402H22"
			(at 1.1811 -4.2291 270)
			(unlocked yes)
			(layer "F.Fab")
			(hide yes)
			(effects
				(font
					(size 1.016 1.016)
					(thickness 0.1524)
				)
			)
		)
		(duplicate_pad_numbers_are_jumpers no)
		(fp_rect
			(start -0.4318 0.9525)
			(end 0.4318 -0.9525)
			(stroke
				(width 0)
				(type default)
			)
			(fill no)
			(layer "F.CrtYd")
		)
		(fp_rect
			(start -0.4318 0.9525)
			(end 0.4318 -0.9525)
			(stroke
				(width 0)
				(type default)
			)
			(fill no)
			(layer "F.Fab")
		)
		(pad "1" smd custom
			(at 0 -0.4445 270)
			(size 0.1524 0.1524)
			(layers "F.Cu" "F.Mask" "F.Paste")
			(net "SAS2X28_DRIVE_RX_N_B4")
			(options
				(clearance outline)
				(anchor circle)
			)
			(primitives
				(gr_poly
					(pts
						(arc
							(start 0.3048 -0.2032)
							(mid 0.275042 -0.275042)
							(end 0.2032 -0.3048)
						)
						(arc
							(start -0.2032 -0.3048)
							(mid -0.275042 -0.275042)
							(end -0.3048 -0.2032)
						)
						(arc
							(start -0.3048 0.2032)
							(mid -0.275042 0.275042)
							(end -0.2032 0.3048)
						)
						(arc
							(start 0.2032 0.3048)
							(mid 0.275042 0.275042)
							(end 0.3048 0.2032)
						)
					)
					(width 0)
					(fill yes)
				)
			)
		)
		(pad "2" smd custom
			(at 0 0.4445 270)
			(size 0.1524 0.1524)
			(layers "F.Cu" "F.Mask" "F.Paste")
			(net "SAS2X28_B_HDD4_RX_-")
			(options
				(clearance outline)
				(anchor circle)
			)
			(primitives
				(gr_poly
					(pts
						(arc
							(start 0.3048 -0.2032)
							(mid 0.275042 -0.275042)
							(end 0.2032 -0.3048)
						)
						(arc
							(start -0.2032 -0.3048)
							(mid -0.275042 -0.275042)
							(end -0.3048 -0.2032)
						)
						(arc
							(start -0.3048 0.2032)
							(mid -0.275042 0.275042)
							(end -0.2032 0.3048)
						)
						(arc
							(start 0.2032 0.3048)
							(mid 0.275042 0.275042)
							(end 0.3048 0.2032)
						)
					)
					(width 0)
					(fill yes)
				)
			)
		)
	)
)
